# S9S_MB_2U (Grand Teton) — schematic netlist excerpt (pin names and nets, part order shuffled) for the footprints in the layout excerpt that follows; sources: Cadence DE-HDL packaged netlist, KiCad conversion of 03242023_DA0F0TMBIJ0_F0T_Motherboard_J_brd_V01_OCP.brd

J31  SCONN288_ADR50017P130CC  SCONN288_ADR50017-P130CC IO  pkg DDR288S_1-1VXB  page 112
  VIN_BULK0  = P12V_S3_AUX_CPU1_NVDIMM
  RFU0  = TP_CHH_CPU1_DIMM1_FRU_0
  VIN_MGMT  = P3V3_AUX
  HSCL  = I3C_SPD_DDREFGH_CPU1_LVC1_SCL_6
  HSDA  = I3C_SPD_DDREFGH_CPU1_LVC1_SDA
  VSS0  = GND
  DQ0_A  = M_H_CPU1_SA_DQ<0>
  VSS1  = GND
  DQ1_A  = M_H_CPU1_SA_DQ<1>
  VSS2  = GND
  DQS0_A_T  = M_H_CPU1_SA_DQS_DP<0>
  DQS0_A_C  = M_H_CPU1_SA_DQS_DN<0>
  VSS3  = GND
  DQ4_A  = M_H_CPU1_SA_DQ<4>
  VSS4  = GND
  DQ5_A  = M_H_CPU1_SA_DQ<5>
  VSS5  = GND
  DQ8_A  = M_H_CPU1_SA_DQ<8>
  VSS6  = GND
  DQ9_A  = M_H_CPU1_SA_DQ<9>
  VSS7  = GND
  DQS1_A_T  = M_H_CPU1_SA_DQS_DP<1>
  DQS1_A_C  = M_H_CPU1_SA_DQS_DN<1>
  VSS8  = GND
  DQ12_A  = M_H_CPU1_SA_DQ<12>
  VSS9  = GND
  DQ13_A  = M_H_CPU1_SA_DQ<13>
  VSS10  = GND
  DQ16_A  = M_H_CPU1_SA_DQ<16>
  VSS11  = GND
  DQ17_A  = M_H_CPU1_SA_DQ<17>
  VSS12  = GND
  DQS2_A_T  = M_H_CPU1_SA_DQS_DP<2>
  DQS2_A_C  = M_H_CPU1_SA_DQS_DN<2>
  VSS13  = GND
  DQ20_A  = M_H_CPU1_SA_DQ<20>
  VSS14  = GND
  DQ21_A  = M_H_CPU1_SA_DQ<21>
  VSS15  = GND
  DQ24_A  = M_H_CPU1_SA_DQ<24>
  VSS16  = GND
  DQ25_A  = M_H_CPU1_SA_DQ<25>
  VSS17  = GND
  DQS3_A_T  = M_H_CPU1_SA_DQS_DP<3>
  DQS3_A_C  = M_H_CPU1_SA_DQS_DN<3>
  VSS18  = GND
  DQ28_A  = M_H_CPU1_SA_DQ<28>
  VSS19  = GND
  DQ29_A  = M_H_CPU1_SA_DQ<29>
  VSS20  = GND
  CB0_A  = M_H_CPU1_SA_CB<0>
  VSS21  = GND
  CB1_A  = M_H_CPU1_SA_CB<1>
  VSS22  = GND
  DQS4_A_T  = M_H_CPU1_SA_DQS_DP<4>
  DQS4_A_C  = M_H_CPU1_SA_DQS_DN<4>
  VSS23  = GND
  CB4_A  = M_H_CPU1_SA_CB<4>
  VSS24  = GND
  CB5_A  = M_H_CPU1_SA_CB<5>
  VSS25  = GND
  ALERT_N  = M_H_CPU1_ALERT_N
  VSS26  = GND
  CS0_A_N  = M_H_CPU1_SA_CS_N<0>
  VSS27  = GND
  CA0_A  = M_H_CPU1_SA_CA<0>
  VSS28  = GND
  CA2_A  = M_H_CPU1_SA_CA<2>
  VSS29  = GND
  CA4_A  = M_H_CPU1_SA_CA<4>
  VSS30  = GND
  CA6_A  = M_H_CPU1_SA_CA<6>
  VSS31  = GND
  PAR_A  = M_H_CPU1_SA_PAR
  VSS32  = GND
  CA0_B  = M_H_CPU1_SB_CA<0>
  VSS33  = GND
  CA2_B  = M_H_CPU1_SB_CA<2>
  VSS34  = GND
  CA4_B  = M_H_CPU1_SB_CA<4>
  VSS35  = GND
  CA6_B  = M_H_CPU1_SB_CA<6>
  VSS36  = GND
  CS0_B_N  = M_H_CPU1_SB_CS_N<0>
  VSS37  = GND
  \lbd||rsp_a_n\  = M_H_CPU1_SA_RSP<0>
  \lbs||rsp_b_n\  = M_H_CPU1_SB_RSP<0>
  VSS38  = GND
  CB4_B  = M_H_CPU1_SB_CB<4>
  VSS39  = GND
  CB5_B  = M_H_CPU1_SB_CB<5>
  VSS40  = GND
  \dqs9_b_t||tdqs9_b_t||dbi4_b_n\  = M_H_CPU1_SB_DQS_DP<9>
  \dqs9_b_c||tdqs9_b_c\  = M_H_CPU1_SB_DQS_DN<9>
  VSS41  = GND
  CB0_B  = M_H_CPU1_SB_CB<0>
  VSS42  = GND
  CB1_B  = M_H_CPU1_SB_CB<1>
  VSS43  = GND
  DQ0_B  = M_H_CPU1_SB_DQ<0>
  VSS44  = GND
  DQ1_B  = M_H_CPU1_SB_DQ<1>
  VSS45  = GND
  DQS0_B_T  = M_H_CPU1_SB_DQS_DP<0>
  DQS0_B_C  = M_H_CPU1_SB_DQS_DN<0>
  VSS46  = GND
  DQ4_B  = M_H_CPU1_SB_DQ<4>
  VSS47  = GND
  DQ5_B  = M_H_CPU1_SB_DQ<5>
  VSS48  = GND
  DQ8_B  = M_H_CPU1_SB_DQ<8>
  VSS49  = GND
  DQ9_B  = M_H_CPU1_SB_DQ<9>
  VSS50  = GND
  DQS1_B_T  = M_H_CPU1_SB_DQS_DP<1>
  DQS1_B_C  = M_H_CPU1_SB_DQS_DN<1>
  VSS51  = GND
  DQ12_B  = M_H_CPU1_SB_DQ<12>
  VSS52  = GND
  DQ13_B  = M_H_CPU1_SB_DQ<13>
  VSS53  = GND
  DQ16_B  = M_H_CPU1_SB_DQ<16>
  VSS54  = GND
  DQ17_B  = M_H_CPU1_SB_DQ<17>
  VSS55  = GND
  DQS2_B_T  = M_H_CPU1_SB_DQS_DP<2>
  DQS2_B_C  = M_H_CPU1_SB_DQS_DN<2>
  VSS56  = GND
  DQ20_B  = M_H_CPU1_SB_DQ<20>
  VSS57  = GND
  DQ21_B  = M_H_CPU1_SB_DQ<21>
  VSS58  = GND
  DQ24_B  = M_H_CPU1_SB_DQ<24>
  VSS59  = GND
  DQ25_B  = M_H_CPU1_SB_DQ<25>
  VSS60  = GND
  DQS3_B_T  = M_H_CPU1_SB_DQS_DP<3>
  DQS3_B_C  = M_H_CPU1_SB_DQS_DN<3>
  VSS61  = GND
  DQ28_B  = M_H_CPU1_SB_DQ<28>
  VSS62  = GND
  DQ29_B  = M_H_CPU1_SB_DQ<29>
  VSS63  = GND
  RFU1  = TP_CHH_CPU1_DIMM1_FRU_1
  VIN_BULK1  = P12V_S3_AUX_CPU1_NVDIMM
  VIN_BULK2  = P12V_S3_AUX_CPU1_NVDIMM
  \pwr_good||fail_n\  = PWRGD_CHH_CPU1_DIMM1
  HSA  = PD_CHH_CPU1_DIMM1_SAA
  RFU2  = TP_CHH_CPU1_DIMM1_FRU_2
  RFU3  = TP_CHH_CPU1_DIMM1_FRU_3
  VSS64  = GND
  DQ2_A  = M_H_CPU1_SA_DQ<2>
  VSS65  = GND
  DQ3_A  = M_H_CPU1_SA_DQ<3>
  VSS66  = GND
  \dqs5_a_c||tdqs5_a_c||dqs5_a_t||tdqs5_a_t\  = M_H_CPU1_SA_DQS_DN<5>
  \dqs5_a_t||tdqs5_a_t\  = M_H_CPU1_SA_DQS_DP<5>
  VSS67  = GND
  DQ6_A  = M_H_CPU1_SA_DQ<6>
  VSS68  = GND
  DQ7_A  = M_H_CPU1_SA_DQ<7>
  VSS69  = GND
  DQ10_A  = M_H_CPU1_SA_DQ<10>
  VSS70  = GND
  DQ11_A  = M_H_CPU1_SA_DQ<11>
  VSS71  = GND
  \dqs6_a_c||tdqs6_a_c||dqs6_a_t||tdqs6_a_t\  = M_H_CPU1_SA_DQS_DN<6>
  \dqs6_a_t||tdqs6_a_t\  = M_H_CPU1_SA_DQS_DP<6>
  VSS72  = GND
  DQ14_A  = M_H_CPU1_SA_DQ<14>
  VSS73  = GND
  DQ15_A  = M_H_CPU1_SA_DQ<15>
  VSS74  = GND
  DQ18_A  = M_H_CPU1_SA_DQ<18>
  VSS75  = GND
  DQ19_A  = M_H_CPU1_SA_DQ<19>
  VSS76  = GND
  \dqs7_a_c||tdqs7_a_c\  = M_H_CPU1_SA_DQS_DN<7>
  \dqs7_a_t||tdqs7_a_t\  = M_H_CPU1_SA_DQS_DP<7>
  VSS77  = GND
  DQ22_A  = M_H_CPU1_SA_DQ<22>
  VSS78  = GND
  DQ23_A  = M_H_CPU1_SA_DQ<23>
  VSS79  = GND
  DQ26_A  = M_H_CPU1_SA_DQ<26>
  VSS80  = GND
  DQ27_A  = M_H_CPU1_SA_DQ<27>
  VSS81  = GND
  \dqs8_a_c||tdqs8_a_c\  = M_H_CPU1_SA_DQS_DN<8>
  \dqs8_a_t||tdqs8_a_t\  = M_H_CPU1_SA_DQS_DP<8>
  VSS82  = GND
  DQ30_A  = M_H_CPU1_SA_DQ<30>
  VSS83  = GND
  DQ31_A  = M_H_CPU1_SA_DQ<31>
  VSS84  = GND
  CB2_A  = M_H_CPU1_SA_CB<2>
  VSS85  = GND
  CB3_A  = M_H_CPU1_SA_CB<3>
  VSS86  = GND
  \dqs9_a_c||tdqs9_a_c\  = M_H_CPU1_SA_DQS_DN<9>
  \dqs9_a_t||tdqs9_a_t\  = M_H_CPU1_SA_DQS_DP<9>
  VSS87  = GND
  CB6_A  = M_H_CPU1_SA_CB<6>
  VSS88  = GND
  CB7_A  = M_H_CPU1_SA_CB<7>
  VSS89  = GND
  RESET_N  = RST_M_GH_CPU1_FPGA_N
  VSS90  = GND
  CS1_A_N  = M_H_CPU1_SA_CS_N<1>
  VSS91  = GND
  CA1_A  = M_H_CPU1_SA_CA<1>
  VSS92  = GND
  CA3_A  = M_H_CPU1_SA_CA<3>
  VSS93  = GND
  CA5_A  = M_H_CPU1_SA_CA<5>
  VSS94  = GND
  CK_T  = M_H_CPU1_CLK_DP<0>
  CK_C  = M_H_CPU1_CLK_DN<0>
  VSS95  = GND
  RFU4  = TP_CHH_CPU1_DIMM1_FRU_4
  CA1_B  = M_H_CPU1_SB_CA<1>
  VSS96  = GND
  CA3_B  = M_H_CPU1_SB_CA<3>
  VSS97  = GND
  CA5_B  = M_H_CPU1_SB_CA<5>
  VSS98  = GND
  PAR_B  = M_H_CPU1_SB_PAR
  VSS99  = GND
  CS1_B_N  = M_H_CPU1_SB_CS_N<1>
  VSS100  = GND
  RFU5  = TP_CHH_CPU1_DIMM1_FRU_5
  RFU6  = TP_CHH_CPU1_DIMM1_FRU_6
  VSS101  = GND
  CB6_B  = M_H_CPU1_SB_CB<6>
  VSS102  = GND
  CB7_B  = M_H_CPU1_SB_CB<7>
  VSS103  = GND
  DQS4_B_C  = M_H_CPU1_SB_DQS_DN<4>
  DQS4_B_T  = M_H_CPU1_SB_DQS_DP<4>
  VSS104  = GND
  CB2_B  = M_H_CPU1_SB_CB<2>
  VSS105  = GND
  CB3_B  = M_H_CPU1_SB_CB<3>
  VSS106  = GND
  DQ2_B  = M_H_CPU1_SB_DQ<2>
  VSS107  = GND
  DQ3_B  = M_H_CPU1_SB_DQ<3>
  VSS108  = GND
  \dqs5_b_c||tdqs5_b_c\  = M_H_CPU1_SB_DQS_DN<5>
  \dqs5_b_t||tdqs5_b_t\  = M_H_CPU1_SB_DQS_DP<5>
  VSS109  = GND
  DQ6_B  = M_H_CPU1_SB_DQ<6>
  VSS110  = GND
  DQ7_B  = M_H_CPU1_SB_DQ<7>
  VSS111  = GND
  DQ10_B  = M_H_CPU1_SB_DQ<10>
  VSS112  = GND
  DQ11_B  = M_H_CPU1_SB_DQ<11>
  VSS113  = GND
  \dqs6_b_c||tdqs6_b_c\  = M_H_CPU1_SB_DQS_DN<6>
  \dqs6_b_t||tdqs6_b_t\  = M_H_CPU1_SB_DQS_DP<6>
  VSS114  = GND
  DQ14_B  = M_H_CPU1_SB_DQ<14>
  VSS115  = GND
  DQ15_B  = M_H_CPU1_SB_DQ<15>
  VSS116  = GND
  DQ18_B  = M_H_CPU1_SB_DQ<18>
  VSS117  = GND
  DQ19_B  = M_H_CPU1_SB_DQ<19>
  VSS118  = GND
  \dqs7_b_c||tdqs7_b_c\  = M_H_CPU1_SB_DQS_DN<7>
  \dqs7_b_t||tdqs7_b_t\  = M_H_CPU1_SB_DQS_DP<7>
  VSS119  = GND
  DQ22_B  = M_H_CPU1_SB_DQ<22>
  VSS120  = GND
  DQ23_B  = M_H_CPU1_SB_DQ<23>
  VSS121  = GND
  DQ26_B  = M_H_CPU1_SB_DQ<26>
  VSS122  = GND
  DQ27_B  = M_H_CPU1_SB_DQ<27>
  VSS123  = GND
  \dqs8_b_c||tdqs8_b_c\  = M_H_CPU1_SB_DQS_DN<8>
  \dqs8_b_t||tdqs8_b_t\  = M_H_CPU1_SB_DQS_DP<8>
  VSS124  = GND
  DQ30_B  = M_H_CPU1_SB_DQ<30>
  VSS125  = GND
  DQ31_B  = M_H_CPU1_SB_DQ<31>
  VSS126  = GND
  G1  = GND
  G2  = GND
  G3  = GND

(kicad_pcb
	(version 20260206)
	(generator "pcbnew")
	(generator_version "10.0")
	(general
		(thickness 1.6)
		(legacy_teardrops no)
	)
	(paper "A4")
	(title_block
		(title "03242023_DA0F0TMBIJ0_F0T_Motherboard_J_brd_V01_OCP.brd")
		(comment 1 "Grand Teton / footprint 3900 of 6105 (J31), pads 183-228 of 291")
	)
	(layers
		(0 "F.Cu" signal "TOP")
		(4 "In1.Cu" signal "GND")
		(6 "In2.Cu" signal "IN1")
		(8 "In3.Cu" signal "GND1")
		(10 "In4.Cu" signal "IN2")
		(12 "In5.Cu" signal "GND2")
		(14 "In6.Cu" signal "IN3")
		(16 "In7.Cu" signal "GND3")
		(18 "In8.Cu" signal "VCC")
		(20 "In9.Cu" signal "VCC1")
		(22 "In10.Cu" signal "GND4")
		(24 "In11.Cu" signal "IN4")
		(26 "In12.Cu" signal "GND5")
		(28 "In13.Cu" signal "IN5")
		(30 "In14.Cu" signal "GND6")
		(32 "In15.Cu" signal "IN6")
		(34 "In16.Cu" signal "GND7")
		(2 "B.Cu" signal "BOTTOM")
		(9 "F.Adhes" user "F.Adhesive")
		(11 "B.Adhes" user "B.Adhesive")
		(13 "F.Paste" user "Package Geometry/Pastemask Top")
		(15 "B.Paste" user "Package Geometry/Pastemask Bottom")
		(5 "F.SilkS" user "Ref Des/Silkscreen Top")
		(7 "B.SilkS" user "Ref Des/Silkscreen Bottom")
		(1 "F.Mask" user "Board Geometry/Soldermask Top")
		(3 "B.Mask" user "Board Geometry/Soldermask Bottom")
		(17 "Dwgs.User" user "User.Drawings")
		(19 "Cmts.User" user "User.Comments")
		(21 "Eco1.User" user "User.Eco1")
		(23 "Eco2.User" user "User.Eco2")
		(25 "Edge.Cuts" user "Board Geometry/Outline")
		(27 "Margin" user)
		(31 "F.CrtYd" user "Package Geometry/Place Bound Top")
		(29 "B.CrtYd" user "Package Geometry/Place Bound Bottom")
		(35 "F.Fab" user "Ref Des/Assembly Top")
		(33 "B.Fab" user "Ref Des/Assembly Bottom")
	)
	(footprint ""
		(layer "F.Cu")
		(at 213.66988 -258.091686)
		(property "Reference" "J31"
			(at -3.683 -81.702148 0)
			(unlocked yes)
			(layer "F.SilkS")
			(effects
				(font
					(size 0.7874 0.5842)
					(thickness 0.1524)
				)
				(justify left)
			)
		)
		(property "Value" ""
			(at 0 0 0)
			(layer "F.Fab")
			(effects
				(font
					(size 1.27 1.27)
				)
			)
		)
		(duplicate_pad_numbers_are_jumpers no)
		(pad "183" smd rect
			(at 2.050034 -31.025084 270)
			(size 0.519938 1.4986)
			(layers "F.Cu" "F.Mask" "F.Paste")
			(net "M_H_CPU1_SA_DQ<23>")
		)
		(pad "184" smd rect
			(at 2.050034 -30.174946 270)
			(size 0.519938 1.4986)
			(layers "F.Cu" "F.Mask" "F.Paste")
			(net "GND")
		)
		(pad "185" smd rect
			(at 2.050034 -29.325062 270)
			(size 0.519938 1.4986)
			(layers "F.Cu" "F.Mask" "F.Paste")
			(net "M_H_CPU1_SA_DQ<26>")
		)
		(pad "186" smd rect
			(at 2.050034 -28.474924 270)
			(size 0.519938 1.4986)
			(layers "F.Cu" "F.Mask" "F.Paste")
			(net "GND")
		)
		(pad "187" smd rect
			(at 2.050034 -27.62504 270)
			(size 0.519938 1.4986)
			(layers "F.Cu" "F.Mask" "F.Paste")
			(net "M_H_CPU1_SA_DQ<27>")
		)
		(pad "188" smd rect
			(at 2.050034 -26.774902 270)
			(size 0.519938 1.4986)
			(layers "F.Cu" "F.Mask" "F.Paste")
			(net "GND")
		)
		(pad "189" smd rect
			(at 2.050034 -25.925018 270)
			(size 0.519938 1.4986)
			(layers "F.Cu" "F.Mask" "F.Paste")
			(net "M_H_CPU1_SA_DQS_DN<8>")
		)
		(pad "190" smd rect
			(at 2.050034 -25.07488 270)
			(size 0.519938 1.4986)
			(layers "F.Cu" "F.Mask" "F.Paste")
			(net "M_H_CPU1_SA_DQS_DP<8>")
		)
		(pad "191" smd rect
			(at 2.050034 -24.224996 270)
			(size 0.519938 1.4986)
			(layers "F.Cu" "F.Mask" "F.Paste")
			(net "GND")
		)
		(pad "192" smd rect
			(at 2.050034 -23.375112 270)
			(size 0.519938 1.4986)
			(layers "F.Cu" "F.Mask" "F.Paste")
			(net "M_H_CPU1_SA_DQ<30>")
		)
		(pad "193" smd rect
			(at 2.050034 -22.524974 270)
			(size 0.519938 1.4986)
			(layers "F.Cu" "F.Mask" "F.Paste")
			(net "GND")
		)
		(pad "194" smd rect
			(at 2.050034 -21.67509 270)
			(size 0.519938 1.4986)
			(layers "F.Cu" "F.Mask" "F.Paste")
			(net "M_H_CPU1_SA_DQ<31>")
		)
		(pad "195" smd rect
			(at 2.050034 -20.824952 270)
			(size 0.519938 1.4986)
			(layers "F.Cu" "F.Mask" "F.Paste")
			(net "GND")
		)
		(pad "196" smd rect
			(at 2.050034 -19.975068 270)
			(size 0.519938 1.4986)
			(layers "F.Cu" "F.Mask" "F.Paste")
			(net "M_H_CPU1_SA_CB<2>")
		)
		(pad "197" smd rect
			(at 2.050034 -19.12493 270)
			(size 0.519938 1.4986)
			(layers "F.Cu" "F.Mask" "F.Paste")
			(net "GND")
		)
		(pad "198" smd rect
			(at 2.050034 -18.275046 270)
			(size 0.519938 1.4986)
			(layers "F.Cu" "F.Mask" "F.Paste")
			(net "M_H_CPU1_SA_CB<3>")
		)
		(pad "199" smd rect
			(at 2.050034 -17.424908 270)
			(size 0.519938 1.4986)
			(layers "F.Cu" "F.Mask" "F.Paste")
			(net "GND")
		)
		(pad "200" smd rect
			(at 2.050034 -16.575024 270)
			(size 0.519938 1.4986)
			(layers "F.Cu" "F.Mask" "F.Paste")
			(net "M_H_CPU1_SA_DQS_DN<9>")
		)
		(pad "201" smd rect
			(at 2.050034 -15.724886 270)
			(size 0.519938 1.4986)
			(layers "F.Cu" "F.Mask" "F.Paste")
			(net "M_H_CPU1_SA_DQS_DP<9>")
		)
		(pad "202" smd rect
			(at 2.050034 -14.875002 270)
			(size 0.519938 1.4986)
			(layers "F.Cu" "F.Mask" "F.Paste")
			(net "GND")
		)
		(pad "203" smd rect
			(at 2.050034 -14.025118 270)
			(size 0.519938 1.4986)
			(layers "F.Cu" "F.Mask" "F.Paste")
			(net "M_H_CPU1_SA_CB<6>")
		)
		(pad "204" smd rect
			(at 2.050034 -13.17498 270)
			(size 0.519938 1.4986)
			(layers "F.Cu" "F.Mask" "F.Paste")
			(net "GND")
		)
		(pad "205" smd rect
			(at 2.050034 -12.325096 270)
			(size 0.519938 1.4986)
			(layers "F.Cu" "F.Mask" "F.Paste")
			(net "M_H_CPU1_SA_CB<7>")
		)
		(pad "206" smd rect
			(at 2.050034 -11.474958 270)
			(size 0.519938 1.4986)
			(layers "F.Cu" "F.Mask" "F.Paste")
			(net "GND")
		)
		(pad "207" smd rect
			(at 2.050034 -10.625074 270)
			(size 0.519938 1.4986)
			(layers "F.Cu" "F.Mask" "F.Paste")
			(net "RST_M_GH_CPU1_FPGA_N")
		)
		(pad "208" smd rect
			(at 2.050034 -9.774936 270)
			(size 0.519938 1.4986)
			(layers "F.Cu" "F.Mask" "F.Paste")
			(net "GND")
		)
		(pad "209" smd rect
			(at 2.050034 -8.925052 270)
			(size 0.519938 1.4986)
			(layers "F.Cu" "F.Mask" "F.Paste")
			(net "M_H_CPU1_SA_CS_N<1>")
		)
		(pad "210" smd rect
			(at 2.050034 -8.074914 270)
			(size 0.519938 1.4986)
			(layers "F.Cu" "F.Mask" "F.Paste")
			(net "GND")
		)
		(pad "211" smd rect
			(at 2.050034 -7.22503 270)
			(size 0.519938 1.4986)
			(layers "F.Cu" "F.Mask" "F.Paste")
			(net "M_H_CPU1_SA_CA<1>")
		)
		(pad "212" smd rect
			(at 2.050034 -6.374892 270)
			(size 0.519938 1.4986)
			(layers "F.Cu" "F.Mask" "F.Paste")
			(net "GND")
		)
		(pad "213" smd rect
			(at 2.050034 -5.525008 270)
			(size 0.519938 1.4986)
			(layers "F.Cu" "F.Mask" "F.Paste")
			(net "M_H_CPU1_SA_CA<3>")
		)
		(pad "214" smd rect
			(at 2.050034 -4.675124 270)
			(size 0.519938 1.4986)
			(layers "F.Cu" "F.Mask" "F.Paste")
			(net "GND")
		)
		(pad "215" smd rect
			(at 2.050034 -3.824986 270)
			(size 0.519938 1.4986)
			(layers "F.Cu" "F.Mask" "F.Paste")
			(net "M_H_CPU1_SA_CA<5>")
		)
		(pad "216" smd rect
			(at 2.050034 -2.975102 270)
			(size 0.519938 1.4986)
			(layers "F.Cu" "F.Mask" "F.Paste")
			(net "GND")
		)
		(pad "217" smd rect
			(at 2.050034 -2.124964 270)
			(size 0.519938 1.4986)
			(layers "F.Cu" "F.Mask" "F.Paste")
			(net "M_H_CPU1_CLK_DP<0>")
		)
		(pad "218" smd rect
			(at 2.050034 -1.27508 270)
			(size 0.519938 1.4986)
			(layers "F.Cu" "F.Mask" "F.Paste")
			(net "M_H_CPU1_CLK_DN<0>")
		)
		(pad "219" smd rect
			(at 2.050034 -0.424942 270)
			(size 0.519938 1.4986)
			(layers "F.Cu" "F.Mask" "F.Paste")
			(net "GND")
		)
		(pad "220" smd rect
			(at 2.050034 5.525008 270)
			(size 0.519938 1.4986)
			(layers "F.Cu" "F.Mask" "F.Paste")
			(net "TP_CHH_CPU1_DIMM1_FRU_4")
		)
		(pad "221" smd rect
			(at 2.050034 6.374892 270)
			(size 0.519938 1.4986)
			(layers "F.Cu" "F.Mask" "F.Paste")
			(net "M_H_CPU1_SB_CA<1>")
		)
		(pad "222" smd rect
			(at 2.050034 7.22503 270)
			(size 0.519938 1.4986)
			(layers "F.Cu" "F.Mask" "F.Paste")
			(net "GND")
		)
		(pad "223" smd rect
			(at 2.050034 8.074914 270)
			(size 0.519938 1.4986)
			(layers "F.Cu" "F.Mask" "F.Paste")
			(net "M_H_CPU1_SB_CA<3>")
		)
		(pad "224" smd rect
			(at 2.050034 8.925052 270)
			(size 0.519938 1.4986)
			(layers "F.Cu" "F.Mask" "F.Paste")
			(net "GND")
		)
		(pad "225" smd rect
			(at 2.050034 9.774936 270)
			(size 0.519938 1.4986)
			(layers "F.Cu" "F.Mask" "F.Paste")
			(net "M_H_CPU1_SB_CA<5>")
		)
		(pad "226" smd rect
			(at 2.050034 10.625074 270)
			(size 0.519938 1.4986)
			(layers "F.Cu" "F.Mask" "F.Paste")
			(net "GND")
		)
		(pad "227" smd rect
			(at 2.050034 11.474958 270)
			(size 0.519938 1.4986)
			(layers "F.Cu" "F.Mask" "F.Paste")
			(net "M_H_CPU1_SB_PAR")
		)
		(pad "228" smd rect
			(at 2.050034 12.325096 270)
			(size 0.519938 1.4986)
			(layers "F.Cu" "F.Mask" "F.Paste")
			(net "GND")
		)
	)
)
